# T6G (Grand Teton) — schematic netlist excerpt (pin names and nets, part order shuffled) for the footprints in the layout excerpt that follows; sources: Cadence DE-HDL packaged netlist, KiCad conversion of 04192023_DAF0TMB3IC0_F0TG_MB_C_brd_V02_OCP.brd

R4563  Q_RES  33.2 1% CHIP  pkg 0402LF  page 81 : A = SWB_HSC_PWRGD_ISO_R ; B = SWB_HSC_PWRGD_ISO
R14  Q_RES  0 5% CHIP  pkg 0402LF  page 85 : A = JTAG_PLD_TMS ; B = JTAG_SCM_PLD_TMS

(kicad_pcb
	(version 20260206)
	(generator "pcbnew")
	(generator_version "10.0")
	(general
		(thickness 1.6)
		(legacy_teardrops no)
	)
	(paper "A4")
	(title_block
		(title "04192023_DAF0TMB3IC0_F0TG_MB_C_brd_V02_OCP.brd")
		(comment 1 "Grand Teton / footprints 5380-5381 of 8354")
	)
	(layers
		(0 "F.Cu" signal "TOP")
		(4 "In1.Cu" signal "GND")
		(6 "In2.Cu" signal "IN1")
		(8 "In3.Cu" signal "GND1")
		(10 "In4.Cu" signal "IN2")
		(12 "In5.Cu" signal "GND2")
		(14 "In6.Cu" signal "IN3")
		(16 "In7.Cu" signal "GND3")
		(18 "In8.Cu" signal "VCC")
		(20 "In9.Cu" signal "VCC1")
		(22 "In10.Cu" signal "GND4")
		(24 "In11.Cu" signal "IN4")
		(26 "In12.Cu" signal "GND5")
		(28 "In13.Cu" signal "IN5")
		(30 "In14.Cu" signal "GND6")
		(32 "In15.Cu" signal "IN6")
		(34 "In16.Cu" signal "GND7")
		(2 "B.Cu" signal "BOTTOM")
		(9 "F.Adhes" user "F.Adhesive")
		(11 "B.Adhes" user "B.Adhesive")
		(13 "F.Paste" user "Package Geometry/Pastemask Top")
		(15 "B.Paste" user "Package Geometry/Pastemask Bottom")
		(5 "F.SilkS" user "Ref Des/Silkscreen Top")
		(7 "B.SilkS" user "Ref Des/Silkscreen Bottom")
		(1 "F.Mask" user "Board Geometry/Soldermask Top")
		(3 "B.Mask" user "Board Geometry/Soldermask Bottom")
		(17 "Dwgs.User" user "User.Drawings")
		(19 "Cmts.User" user "User.Comments")
		(21 "Eco1.User" user "User.Eco1")
		(23 "Eco2.User" user "User.Eco2")
		(25 "Edge.Cuts" user "Board Geometry/Outline")
		(27 "Margin" user)
		(31 "F.CrtYd" user "Package Geometry/Place Bound Top")
		(29 "B.CrtYd" user "Package Geometry/Place Bound Bottom")
		(35 "F.Fab" user "Ref Des/Assembly Top")
		(33 "B.Fab" user "Ref Des/Assembly Bottom")
	)
	(footprint ""
		(layer "B.Cu")
		(at 141.977872 -64.04229 90)
		(property "Reference" "R14"
			(at 0 0 90)
			(layer "B.SilkS")
			(hide yes)
			(effects
				(font
					(size 1.27 1.27)
				)
				(justify mirror)
			)
		)
		(property "Value" ""
			(at 0 0 90)
			(layer "B.Fab")
			(effects
				(font
					(size 1.27 1.27)
				)
				(justify mirror)
			)
		)
		(duplicate_pad_numbers_are_jumpers no)
		(fp_line
			(start 0.7874 -0.4064)
			(end -0.7874 -0.4064)
			(stroke
				(width 0.1524)
				(type default)
			)
			(layer "B.SilkS")
		)
		(fp_line
			(start -0.7874 -0.4064)
			(end -0.7874 0.4064)
			(stroke
				(width 0.1524)
				(type default)
			)
			(layer "B.SilkS")
		)
		(fp_line
			(start 0.7874 0.4064)
			(end 0.7874 -0.4064)
			(stroke
				(width 0.1524)
				(type default)
			)
			(layer "B.SilkS")
		)
		(fp_line
			(start -0.7874 0.4064)
			(end 0.7874 0.4064)
			(stroke
				(width 0.1524)
				(type default)
			)
			(layer "B.SilkS")
		)
		(fp_line
			(start 0.67945 -0.305054)
			(end 0.12065 -0.305054)
			(stroke
				(width 0.1)
				(type default)
			)
			(layer "B.Fab")
		)
		(fp_line
			(start 0.12065 -0.305054)
			(end 0.12065 -0.2794)
			(stroke
				(width 0.1)
				(type default)
			)
			(layer "B.Fab")
		)
		(fp_line
			(start -0.12065 -0.3048)
			(end -0.67945 -0.3048)
			(stroke
				(width 0.1)
				(type default)
			)
			(layer "B.Fab")
		)
		(fp_line
			(start -0.67945 -0.3048)
			(end -0.67945 0.3048)
			(stroke
				(width 0.1)
				(type default)
			)
			(layer "B.Fab")
		)
		(fp_line
			(start 0.12065 -0.2794)
			(end -0.12065 -0.2794)
			(stroke
				(width 0.1)
				(type default)
			)
			(layer "B.Fab")
		)
		(fp_line
			(start -0.12065 -0.2794)
			(end -0.12065 -0.3048)
			(stroke
				(width 0.1)
				(type default)
			)
			(layer "B.Fab")
		)
		(fp_line
			(start 0.12065 0.2794)
			(end 0.12065 0.3048)
			(stroke
				(width 0.1)
				(type default)
			)
			(layer "B.Fab")
		)
		(fp_line
			(start -0.120396 0.2794)
			(end 0.12065 0.2794)
			(stroke
				(width 0.1)
				(type default)
			)
			(layer "B.Fab")
		)
		(fp_line
			(start 0.67945 0.3048)
			(end 0.67945 -0.305054)
			(stroke
				(width 0.1)
				(type default)
			)
			(layer "B.Fab")
		)
		(fp_line
			(start 0.12065 0.3048)
			(end 0.67945 0.3048)
			(stroke
				(width 0.1)
				(type default)
			)
			(layer "B.Fab")
		)
		(fp_line
			(start -0.120396 0.3048)
			(end -0.120396 0.2794)
			(stroke
				(width 0.1)
				(type default)
			)
			(layer "B.Fab")
		)
		(fp_line
			(start -0.67945 0.3048)
			(end -0.120396 0.3048)
			(stroke
				(width 0.1)
				(type default)
			)
			(layer "B.Fab")
		)
		(pad "1" smd circle
			(at 0.40005 0 270)
			(size 0 0)
			(layers "B.Cu" "B.Mask" "B.Paste")
			(net "JTAG_PLD_TMS")
		)
		(pad "2" smd circle
			(at -0.40005 0 270)
			(size 0 0)
			(layers "B.Cu" "B.Mask" "B.Paste")
			(net "JTAG_SCM_PLD_TMS")
		)
	)
	(footprint ""
		(layer "B.Cu")
		(at 200.952608 -121.753376 180)
		(property "Reference" "R4563"
			(at 0 0 0)
			(layer "B.SilkS")
			(hide yes)
			(effects
				(font
					(size 1.27 1.27)
				)
				(justify mirror)
			)
		)
		(property "Value" ""
			(at 0 0 0)
			(layer "B.Fab")
			(effects
				(font
					(size 1.27 1.27)
				)
				(justify mirror)
			)
		)
		(duplicate_pad_numbers_are_jumpers no)
		(fp_line
			(start 0.7874 0.4064)
			(end 0.7874 -0.4064)
			(stroke
				(width 0.1524)
				(type default)
			)
			(layer "B.SilkS")
		)
		(fp_line
			(start 0.7874 -0.4064)
			(end -0.7874 -0.4064)
			(stroke
				(width 0.1524)
				(type default)
			)
			(layer "B.SilkS")
		)
		(fp_line
			(start -0.7874 0.4064)
			(end 0.7874 0.4064)
			(stroke
				(width 0.1524)
				(type default)
			)
			(layer "B.SilkS")
		)
		(fp_line
			(start -0.7874 -0.4064)
			(end -0.7874 0.4064)
			(stroke
				(width 0.1524)
				(type default)
			)
			(layer "B.SilkS")
		)
		(fp_line
			(start 0.67945 0.3048)
			(end 0.67945 -0.305054)
			(stroke
				(width 0.1)
				(type default)
			)
			(layer "B.Fab")
		)
		(fp_line
			(start 0.67945 -0.305054)
			(end 0.12065 -0.305054)
			(stroke
				(width 0.1)
				(type default)
			)
			(layer "B.Fab")
		)
		(fp_line
			(start 0.12065 0.3048)
			(end 0.67945 0.3048)
			(stroke
				(width 0.1)
				(type default)
			)
			(layer "B.Fab")
		)
		(fp_line
			(start 0.12065 0.2794)
			(end 0.12065 0.3048)
			(stroke
				(width 0.1)
				(type default)
			)
			(layer "B.Fab")
		)
		(fp_line
			(start 0.12065 -0.2794)
			(end -0.12065 -0.2794)
			(stroke
				(width 0.1)
				(type default)
			)
			(layer "B.Fab")
		)
		(fp_line
			(start 0.12065 -0.305054)
			(end 0.12065 -0.2794)
			(stroke
				(width 0.1)
				(type default)
			)
			(layer "B.Fab")
		)
		(fp_line
			(start -0.120396 0.3048)
			(end -0.120396 0.2794)
			(stroke
				(width 0.1)
				(type default)
			)
			(layer "B.Fab")
		)
		(fp_line
			(start -0.120396 0.2794)
			(end 0.12065 0.2794)
			(stroke
				(width 0.1)
				(type default)
			)
			(layer "B.Fab")
		)
		(fp_line
			(start -0.12065 -0.2794)
			(end -0.12065 -0.3048)
			(stroke
				(width 0.1)
				(type default)
			)
			(layer "B.Fab")
		)
		(fp_line
			(start -0.12065 -0.3048)
			(end -0.67945 -0.3048)
			(stroke
				(width 0.1)
				(type default)
			)
			(layer "B.Fab")
		)
		(fp_line
			(start -0.67945 0.3048)
			(end -0.120396 0.3048)
			(stroke
				(width 0.1)
				(type default)
			)
			(layer "B.Fab")
		)
		(fp_line
			(start -0.67945 -0.3048)
			(end -0.67945 0.3048)
			(stroke
				(width 0.1)
				(type default)
			)
			(layer "B.Fab")
		)
		(pad "1" smd circle
			(at 0.40005 0)
			(size 0 0)
			(layers "B.Cu" "B.Mask" "B.Paste")
			(net "SWB_HSC_PWRGD_ISO_R")
		)
		(pad "2" smd circle
			(at -0.40005 0)
			(size 0 0)
			(layers "B.Cu" "B.Mask" "B.Paste")
			(net "SWB_HSC_PWRGD_ISO")
		)
	)
)
